(kicad_pcb
	(version 20260206)
	(generator "pcbnew")
	(generator_version "10.0")
	(general
		(thickness 1.6)
		(legacy_teardrops no)
	)
	(paper "A4")
	(title_block
		(title "baseboard — 13948-1b.1110WZS1818.brd")
		(comment 1 "Honey Badger (Wiwynn) / footprints 1426-1434 of 2523")
	)
	(layers
		(0 "F.Cu" signal "TOP")
		(4 "In1.Cu" signal "L2GND")
		(6 "In2.Cu" signal "L3")
		(8 "In3.Cu" signal "L4VCC")
		(10 "In4.Cu" signal "L5VCC")
		(12 "In5.Cu" signal "L6")
		(14 "In6.Cu" signal "L7GND")
		(2 "B.Cu" signal "BOTTOM")
		(9 "F.Adhes" user "F.Adhesive")
		(11 "B.Adhes" user "B.Adhesive")
		(13 "F.Paste" user "Package Geometry/Pastemask Top")
		(15 "B.Paste" user "Package Geometry/Pastemask Bottom")
		(5 "F.SilkS" user "Ref Des/Silkscreen Top")
		(7 "B.SilkS" user "Ref Des/Silkscreen Bottom")
		(1 "F.Mask" user "Board Geometry/Soldermask Top")
		(3 "B.Mask" user "Board Geometry/Soldermask Bottom")
		(17 "Dwgs.User" user "User.Drawings")
		(19 "Cmts.User" user "User.Comments")
		(21 "Eco1.User" user "User.Eco1")
		(23 "Eco2.User" user "User.Eco2")
		(25 "Edge.Cuts" user "Board Geometry/Outline")
		(27 "Margin" user)
		(31 "F.CrtYd" user "Package Geometry/Place Bound Top")
		(29 "B.CrtYd" user "Package Geometry/Place Bound Bottom")
		(35 "F.Fab" user "Ref Des/Assembly Top")
		(33 "B.Fab" user "Ref Des/Assembly Bottom")
	)
	(footprint ""
		(layer "F.Cu")
		(at 115.57 -28.321 180)
		(property "Reference" "SR663"
			(at 0 0 180)
			(layer "F.SilkS")
			(hide yes)
			(effects
				(font
					(size 1.27 1.27)
				)
			)
		)
		(property "Value" "10KR2F-2-GP"
			(at 0.064008 -3.993896 180)
			(unlocked yes)
			(layer "F.Fab")
			(hide yes)
			(effects
				(font
					(size 1.016 1.016)
					(thickness 0.1524)
				)
			)
		)
		(property "Device Type" "R402H16"
			(at 0.064008 -5.517896 180)
			(unlocked yes)
			(layer "F.Fab")
			(hide yes)
			(effects
				(font
					(size 1.016 1.016)
					(thickness 0.1524)
				)
			)
		)
		(duplicate_pad_numbers_are_jumpers no)
		(fp_line
			(start 0.508 -0.9398)
			(end -0.508 -0.9398)
			(stroke
				(width 0.1524)
				(type default)
			)
			(layer "F.SilkS")
		)
		(fp_line
			(start -0.508 -0.9398)
			(end -0.508 0.9398)
			(stroke
				(width 0.1524)
				(type default)
			)
			(layer "F.SilkS")
		)
		(fp_rect
			(start -0.508 0.9398)
			(end 0.508 -0.9398)
			(stroke
				(width 0)
				(type default)
			)
			(fill no)
			(layer "F.CrtYd")
		)
		(fp_rect
			(start -0.508 0.9398)
			(end 0.508 -0.9398)
			(stroke
				(width 0)
				(type default)
			)
			(fill no)
			(layer "F.Fab")
		)
		(pad "1" smd custom
			(at 0 -0.4445 180)
			(size 0.1397 0.1397)
			(layers "F.Cu" "F.Mask" "F.Paste")
			(net "P1V8_C")
			(options
				(clearance outline)
				(anchor circle)
			)
			(primitives
				(gr_poly
					(pts
						(arc
							(start -0.1778 -0.2794)
							(mid -0.249642 -0.249642)
							(end -0.2794 -0.1778)
						)
						(arc
							(start -0.2794 0.1778)
							(mid -0.249642 0.249642)
							(end -0.1778 0.2794)
						)
						(arc
							(start 0.1778 0.2794)
							(mid 0.249642 0.249642)
							(end 0.2794 0.1778)
						)
						(arc
							(start 0.2794 -0.1778)
							(mid 0.249642 -0.249642)
							(end 0.1778 -0.2794)
						)
					)
					(width 0)
					(fill yes)
				)
			)
		)
		(pad "2" smd custom
			(at 0 0.4445 180)
			(size 0.1397 0.1397)
			(layers "F.Cu" "F.Mask" "F.Paste")
			(net "SYS_DBMODE2")
			(options
				(clearance outline)
				(anchor circle)
			)
			(primitives
				(gr_poly
					(pts
						(arc
							(start -0.1778 -0.2794)
							(mid -0.249642 -0.249642)
							(end -0.2794 -0.1778)
						)
						(arc
							(start -0.2794 0.1778)
							(mid -0.249642 0.249642)
							(end -0.1778 0.2794)
						)
						(arc
							(start 0.1778 0.2794)
							(mid 0.249642 0.249642)
							(end 0.2794 0.1778)
						)
						(arc
							(start 0.2794 -0.1778)
							(mid 0.249642 -0.249642)
							(end 0.1778 -0.2794)
						)
					)
					(width 0)
					(fill yes)
				)
			)
		)
	)
	(footprint ""
		(layer "F.Cu")
		(at 267.843 -73.025 90)
		(property "Reference" "C256"
			(at 0 0 90)
			(layer "F.SilkS")
			(hide yes)
			(effects
				(font
					(size 1.27 1.27)
				)
			)
		)
		(property "Value" "SCD1U25V2KX-2-GP"
			(at 1.1811 -2.7051 90)
			(unlocked yes)
			(layer "F.Fab")
			(hide yes)
			(effects
				(font
					(size 1.016 1.016)
					(thickness 0.1524)
				)
			)
		)
		(property "Device Type" "C402H22"
			(at 1.1811 -4.2291 90)
			(unlocked yes)
			(layer "F.Fab")
			(hide yes)
			(effects
				(font
					(size 1.016 1.016)
					(thickness 0.1524)
				)
			)
		)
		(duplicate_pad_numbers_are_jumpers no)
		(fp_rect
			(start -0.4318 0.9525)
			(end 0.4318 -0.9525)
			(stroke
				(width 0)
				(type default)
			)
			(fill no)
			(layer "F.CrtYd")
		)
		(fp_rect
			(start -0.4318 0.9525)
			(end 0.4318 -0.9525)
			(stroke
				(width 0)
				(type default)
			)
			(fill no)
			(layer "F.Fab")
		)
		(pad "1" smd custom
			(at 0 -0.4445 90)
			(size 0.1524 0.1524)
			(layers "F.Cu" "F.Mask" "F.Paste")
			(net "P12V_MSB")
			(options
				(clearance outline)
				(anchor circle)
			)
			(primitives
				(gr_poly
					(pts
						(arc
							(start 0.3048 -0.2032)
							(mid 0.275042 -0.275042)
							(end 0.2032 -0.3048)
						)
						(arc
							(start -0.2032 -0.3048)
							(mid -0.275042 -0.275042)
							(end -0.3048 -0.2032)
						)
						(arc
							(start -0.3048 0.2032)
							(mid -0.275042 0.275042)
							(end -0.2032 0.3048)
						)
						(arc
							(start 0.2032 0.3048)
							(mid 0.275042 0.275042)
							(end 0.3048 0.2032)
						)
					)
					(width 0)
					(fill yes)
				)
			)
		)
		(pad "2" smd custom
			(at 0 0.4445 90)
			(size 0.1524 0.1524)
			(layers "F.Cu" "F.Mask" "F.Paste")
			(net "GND")
			(options
				(clearance outline)
				(anchor circle)
			)
			(primitives
				(gr_poly
					(pts
						(arc
							(start 0.3048 -0.2032)
							(mid 0.275042 -0.275042)
							(end 0.2032 -0.3048)
						)
						(arc
							(start -0.2032 -0.3048)
							(mid -0.275042 -0.275042)
							(end -0.3048 -0.2032)
						)
						(arc
							(start -0.3048 0.2032)
							(mid -0.275042 0.275042)
							(end -0.2032 0.3048)
						)
						(arc
							(start 0.2032 0.3048)
							(mid 0.275042 0.275042)
							(end 0.3048 0.2032)
						)
					)
					(width 0)
					(fill yes)
				)
			)
		)
	)
	(footprint ""
		(layer "F.Cu")
		(at 184.077864 -24.075136)
		(property "Reference" "TP129"
			(at 0 0 0)
			(layer "F.SilkS")
			(hide yes)
			(effects
				(font
					(size 1.27 1.27)
				)
			)
		)
		(property "Value" "TPAD28"
			(at 0.0127 -1.8034 0)
			(unlocked yes)
			(layer "F.Fab")
			(hide yes)
			(effects
				(font
					(size 1.016 1.016)
					(thickness 0.1524)
				)
			)
		)
		(property "Device Type" "TPAD28"
			(at 0.0127 -3.3274 0)
			(unlocked yes)
			(layer "F.Fab")
			(hide yes)
			(effects
				(font
					(size 1.016 1.016)
					(thickness 0.1524)
				)
			)
		)
		(duplicate_pad_numbers_are_jumpers no)
		(fp_poly
			(pts
				(arc
					(start 0.3556 0)
					(mid -0.3556 0)
					(end 0.3556 0)
				)
			)
			(stroke
				(width 0)
				(type default)
			)
			(fill no)
			(layer "F.CrtYd")
		)
		(fp_poly
			(pts
				(arc
					(start 0.6096 0)
					(mid -0.6096 0)
					(end 0.6096 0)
				)
			)
			(stroke
				(width 0)
				(type default)
			)
			(fill no)
			(layer "F.Fab")
		)
		(pad "1" smd circle
			(at 0 0)
			(size 0.7112 0.7112)
			(layers "F.Cu" "F.Mask" "F.Paste")
			(net "RMII_BMC_MDIO_R")
		)
	)
	(footprint ""
		(layer "F.Cu")
		(at 186.055 -122.047 180)
		(property "Reference" "PR170"
			(at 0 0 180)
			(layer "F.SilkS")
			(hide yes)
			(effects
				(font
					(size 1.27 1.27)
				)
			)
		)
		(property "Value" "100KR2F-L1-GP"
			(at 0.064008 -3.993896 180)
			(unlocked yes)
			(layer "F.Fab")
			(hide yes)
			(effects
				(font
					(size 1.016 1.016)
					(thickness 0.1524)
				)
			)
		)
		(property "Device Type" "R402H16"
			(at 0.064008 -5.517896 180)
			(unlocked yes)
			(layer "F.Fab")
			(hide yes)
			(effects
				(font
					(size 1.016 1.016)
					(thickness 0.1524)
				)
			)
		)
		(duplicate_pad_numbers_are_jumpers no)
		(fp_line
			(start 0.508 -0.9398)
			(end -0.508 -0.9398)
			(stroke
				(width 0.1524)
				(type default)
			)
			(layer "F.SilkS")
		)
		(fp_line
			(start -0.508 -0.9398)
			(end -0.508 0.9398)
			(stroke
				(width 0.1524)
				(type default)
			)
			(layer "F.SilkS")
		)
		(fp_rect
			(start -0.508 0.9398)
			(end 0.508 -0.9398)
			(stroke
				(width 0)
				(type default)
			)
			(fill no)
			(layer "F.CrtYd")
		)
		(fp_rect
			(start -0.508 0.9398)
			(end 0.508 -0.9398)
			(stroke
				(width 0)
				(type default)
			)
			(fill no)
			(layer "F.Fab")
		)
		(pad "1" smd custom
			(at 0 -0.4445 180)
			(size 0.1397 0.1397)
			(layers "F.Cu" "F.Mask" "F.Paste")
			(net "PMU_PLTRST#")
			(options
				(clearance outline)
				(anchor circle)
			)
			(primitives
				(gr_poly
					(pts
						(arc
							(start -0.1778 -0.2794)
							(mid -0.249642 -0.249642)
							(end -0.2794 -0.1778)
						)
						(arc
							(start -0.2794 0.1778)
							(mid -0.249642 0.249642)
							(end -0.1778 0.2794)
						)
						(arc
							(start 0.1778 0.2794)
							(mid 0.249642 0.249642)
							(end 0.2794 0.1778)
						)
						(arc
							(start 0.2794 -0.1778)
							(mid 0.249642 -0.249642)
							(end 0.1778 -0.2794)
						)
					)
					(width 0)
					(fill yes)
				)
			)
		)
		(pad "2" smd custom
			(at 0 0.4445 180)
			(size 0.1397 0.1397)
			(layers "F.Cu" "F.Mask" "F.Paste")
			(net "GND")
			(options
				(clearance outline)
				(anchor circle)
			)
			(primitives
				(gr_poly
					(pts
						(arc
							(start -0.1778 -0.2794)
							(mid -0.249642 -0.249642)
							(end -0.2794 -0.1778)
						)
						(arc
							(start -0.2794 0.1778)
							(mid -0.249642 0.249642)
							(end -0.1778 0.2794)
						)
						(arc
							(start 0.1778 0.2794)
							(mid 0.249642 0.249642)
							(end 0.2794 0.1778)
						)
						(arc
							(start 0.2794 -0.1778)
							(mid 0.249642 -0.249642)
							(end 0.1778 -0.2794)
						)
					)
					(width 0)
					(fill yes)
				)
			)
		)
	)
	(footprint ""
		(layer "F.Cu")
		(at 266.319 -234.569 -90)
		(property "Reference" "PR84"
			(at 0 0 270)
			(layer "F.SilkS")
			(hide yes)
			(effects
				(font
					(size 1.27 1.27)
				)
			)
		)
		(property "Value" "0R6J-3-GP"
			(at -0.0508 -4.8514 270)
			(unlocked yes)
			(layer "F.Fab")
			(hide yes)
			(effects
				(font
					(size 1.016 1.016)
					(thickness 0.1524)
				)
			)
		)
		(property "Device Type" "R1206H28"
			(at 0 -6.3754 270)
			(unlocked yes)
			(layer "F.Fab")
			(hide yes)
			(effects
				(font
					(size 1.016 1.016)
					(thickness 0.1524)
				)
			)
		)
		(duplicate_pad_numbers_are_jumpers no)
		(fp_line
			(start -1.016 2.2352)
			(end -1.016 -2.2352)
			(stroke
				(width 0.1524)
				(type default)
			)
			(layer "F.SilkS")
		)
		(fp_line
			(start 1.016 2.2352)
			(end -1.016 2.2352)
			(stroke
				(width 0.1524)
				(type default)
			)
			(layer "F.SilkS")
		)
		(fp_line
			(start -1.016 -2.2352)
			(end 1.016 -2.2352)
			(stroke
				(width 0.1524)
				(type default)
			)
			(layer "F.SilkS")
		)
		(fp_line
			(start 1.016 -2.2352)
			(end 1.016 2.2352)
			(stroke
				(width 0.1524)
				(type default)
			)
			(layer "F.SilkS")
		)
		(fp_rect
			(start -1.0922 2.3114)
			(end 1.0922 -2.3114)
			(stroke
				(width 0)
				(type default)
			)
			(fill no)
			(layer "F.CrtYd")
		)
		(fp_poly
			(pts
				(xy -1.0922 -2.3114) (xy 1.0922 -2.3114) (xy 1.0922 2.3114) (xy -1.0922 2.3114)
			)
			(stroke
				(width 0)
				(type default)
			)
			(fill no)
			(layer "F.Fab")
		)
		(pad "1" smd rect
			(at 0 -1.397 270)
			(size 1.651 1.27)
			(layers "F.Cu" "F.Mask" "F.Paste")
			(net "P1V8_STBY")
		)
		(pad "2" smd rect
			(at 0 1.397 270)
			(size 1.651 1.27)
			(layers "F.Cu" "F.Mask" "F.Paste")
			(net "TPS74801_P1V26_STBY_IN")
		)
	)
	(footprint ""
		(layer "F.Cu")
		(at 93.472 -10.033 180)
		(property "Reference" "PC203"
			(at 0 0 180)
			(layer "F.SilkS")
			(hide yes)
			(effects
				(font
					(size 1.27 1.27)
				)
			)
		)
		(property "Value" "SC22U6D3V6KX-2-GP"
			(at -0.0762 -5.1308 180)
			(unlocked yes)
			(layer "F.Fab")
			(hide yes)
			(effects
				(font
					(size 1.016 1.016)
					(thickness 0.1524)
				)
			)
		)
		(property "Device Type" "C1206H71"
			(at -0.127 -6.6548 180)
			(unlocked yes)
			(layer "F.Fab")
			(hide yes)
			(effects
				(font
					(size 1.016 1.016)
					(thickness 0.1524)
				)
			)
		)
		(duplicate_pad_numbers_are_jumpers no)
		(fp_line
			(start 1.016 2.2352)
			(end -1.016 2.2352)
			(stroke
				(width 0.1524)
				(type default)
			)
			(layer "F.SilkS")
		)
		(fp_line
			(start 1.016 0.8382)
			(end 1.016 2.2352)
			(stroke
				(width 0.1524)
				(type default)
			)
			(layer "F.SilkS")
		)
		(fp_line
			(start 1.016 -2.2352)
			(end 1.016 -0.8382)
			(stroke
				(width 0.1524)
				(type default)
			)
			(layer "F.SilkS")
		)
		(fp_line
			(start -1.016 2.2352)
			(end -1.016 0.8382)
			(stroke
				(width 0.1524)
				(type default)
			)
			(layer "F.SilkS")
		)
		(fp_line
			(start -1.016 -0.8382)
			(end -1.016 -2.2352)
			(stroke
				(width 0.1524)
				(type default)
			)
			(layer "F.SilkS")
		)
		(fp_line
			(start -1.016 -2.2352)
			(end 1.016 -2.2352)
			(stroke
				(width 0.1524)
				(type default)
			)
			(layer "F.SilkS")
		)
		(fp_rect
			(start -1.0922 2.3114)
			(end 1.0922 -2.3114)
			(stroke
				(width 0)
				(type default)
			)
			(fill no)
			(layer "F.CrtYd")
		)
		(fp_poly
			(pts
				(xy 1.0922 -2.3114) (xy 1.0922 2.3114) (xy -1.0922 2.3114) (xy -1.0922 -2.3114)
			)
			(stroke
				(width 0)
				(type default)
			)
			(fill no)
			(layer "F.Fab")
		)
		(pad "1" smd rect
			(at 0 -1.397 180)
			(size 1.651 1.27)
			(layers "F.Cu" "F.Mask" "F.Paste")
			(net "P0V955_C")
		)
		(pad "2" smd rect
			(at 0 1.397 180)
			(size 1.651 1.27)
			(layers "F.Cu" "F.Mask" "F.Paste")
			(net "GND")
		)
	)
	(footprint ""
		(layer "F.Cu")
		(at 105.80497 -78.105)
		(property "Reference" "STP147"
			(at 0 0 0)
			(layer "F.SilkS")
			(hide yes)
			(effects
				(font
					(size 1.27 1.27)
				)
			)
		)
		(property "Value" "TPAD28"
			(at 0.0127 -1.8034 0)
			(unlocked yes)
			(layer "F.Fab")
			(hide yes)
			(effects
				(font
					(size 1.016 1.016)
					(thickness 0.1524)
				)
			)
		)
		(property "Device Type" "TPAD28"
			(at 0.0127 -3.3274 0)
			(unlocked yes)
			(layer "F.Fab")
			(hide yes)
			(effects
				(font
					(size 1.016 1.016)
					(thickness 0.1524)
				)
			)
		)
		(duplicate_pad_numbers_are_jumpers no)
		(fp_poly
			(pts
				(arc
					(start 0.3556 0)
					(mid -0.3556 0)
					(end 0.3556 0)
				)
			)
			(stroke
				(width 0)
				(type default)
			)
			(fill no)
			(layer "F.CrtYd")
		)
		(fp_poly
			(pts
				(arc
					(start 0.6096 0)
					(mid -0.6096 0)
					(end 0.6096 0)
				)
			)
			(stroke
				(width 0)
				(type default)
			)
			(fill no)
			(layer "F.Fab")
		)
		(pad "1" smd circle
			(at 0 0)
			(size 0.7112 0.7112)
			(layers "F.Cu" "F.Mask" "F.Paste")
			(net "LSI_TRST_N")
		)
	)
	(footprint ""
		(layer "F.Cu")
		(at 262.001 -33.782 -90)
		(property "Reference" "PR44"
			(at 0 0 270)
			(layer "F.SilkS")
			(hide yes)
			(effects
				(font
					(size 1.27 1.27)
				)
			)
		)
		(property "Value" "2K7R2J-GP"
			(at 0.064008 -3.993896 270)
			(unlocked yes)
			(layer "F.Fab")
			(hide yes)
			(effects
				(font
					(size 1.016 1.016)
					(thickness 0.1524)
				)
			)
		)
		(property "Device Type" "R402H16"
			(at 0.064008 -5.517896 270)
			(unlocked yes)
			(layer "F.Fab")
			(hide yes)
			(effects
				(font
					(size 1.016 1.016)
					(thickness 0.1524)
				)
			)
		)
		(duplicate_pad_numbers_are_jumpers no)
		(fp_line
			(start -0.508 -0.9398)
			(end -0.508 0.9398)
			(stroke
				(width 0.1524)
				(type default)
			)
			(layer "F.SilkS")
		)
		(fp_line
			(start 0.508 -0.9398)
			(end -0.508 -0.9398)
			(stroke
				(width 0.1524)
				(type default)
			)
			(layer "F.SilkS")
		)
		(fp_rect
			(start -0.508 0.9398)
			(end 0.508 -0.9398)
			(stroke
				(width 0)
				(type default)
			)
			(fill no)
			(layer "F.CrtYd")
		)
		(fp_rect
			(start -0.508 0.9398)
			(end 0.508 -0.9398)
			(stroke
				(width 0)
				(type default)
			)
			(fill no)
			(layer "F.Fab")
		)
		(pad "1" smd custom
			(at 0 -0.4445 270)
			(size 0.1397 0.1397)
			(layers "F.Cu" "F.Mask" "F.Paste")
			(net "P1V8_STBY_EN")
			(options
				(clearance outline)
				(anchor circle)
			)
			(primitives
				(gr_poly
					(pts
						(arc
							(start -0.1778 -0.2794)
							(mid -0.249642 -0.249642)
							(end -0.2794 -0.1778)
						)
						(arc
							(start -0.2794 0.1778)
							(mid -0.249642 0.249642)
							(end -0.1778 0.2794)
						)
						(arc
							(start 0.1778 0.2794)
							(mid 0.249642 0.249642)
							(end 0.2794 0.1778)
						)
						(arc
							(start 0.2794 -0.1778)
							(mid 0.249642 -0.249642)
							(end 0.1778 -0.2794)
						)
					)
					(width 0)
					(fill yes)
				)
			)
		)
		(pad "2" smd custom
			(at 0 0.4445 270)
			(size 0.1397 0.1397)
			(layers "F.Cu" "F.Mask" "F.Paste")
			(net "AGND_P1V8_STBY")
			(options
				(clearance outline)
				(anchor circle)
			)
			(primitives
				(gr_poly
					(pts
						(arc
							(start -0.1778 -0.2794)
							(mid -0.249642 -0.249642)
							(end -0.2794 -0.1778)
						)
						(arc
							(start -0.2794 0.1778)
							(mid -0.249642 0.249642)
							(end -0.1778 0.2794)
						)
						(arc
							(start 0.1778 0.2794)
							(mid 0.249642 0.249642)
							(end 0.2794 0.1778)
						)
						(arc
							(start 0.2794 -0.1778)
							(mid 0.249642 -0.249642)
							(end 0.1778 -0.2794)
						)
					)
					(width 0)
					(fill yes)
				)
			)
		)
	)
	(footprint ""
		(layer "F.Cu")
		(at 89.662 -226.822 -90)
		(property "Reference" "SR307"
			(at 0 0 270)
			(layer "F.SilkS")
			(hide yes)
			(effects
				(font
					(size 1.27 1.27)
				)
			)
		)
		(property "Value" "0R2J-2-GP"
			(at 0.064008 -3.993896 270)
			(unlocked yes)
			(layer "F.Fab")
			(hide yes)
			(effects
				(font
					(size 1.016 1.016)
					(thickness 0.1524)
				)
			)
		)
		(property "Device Type" "R402H16"
			(at 0.064008 -5.517896 270)
			(unlocked yes)
			(layer "F.Fab")
			(hide yes)
			(effects
				(font
					(size 1.016 1.016)
					(thickness 0.1524)
				)
			)
		)
		(duplicate_pad_numbers_are_jumpers no)
		(fp_line
			(start -0.508 -0.9398)
			(end -0.508 0.9398)
			(stroke
				(width 0.1524)
				(type default)
			)
			(layer "F.SilkS")
		)
		(fp_line
			(start 0.508 -0.9398)
			(end -0.508 -0.9398)
			(stroke
				(width 0.1524)
				(type default)
			)
			(layer "F.SilkS")
		)
		(fp_rect
			(start -0.508 0.9398)
			(end 0.508 -0.9398)
			(stroke
				(width 0)
				(type default)
			)
			(fill no)
			(layer "F.CrtYd")
		)
		(fp_rect
			(start -0.508 0.9398)
			(end 0.508 -0.9398)
			(stroke
				(width 0)
				(type default)
			)
			(fill no)
			(layer "F.Fab")
		)
		(pad "1" smd custom
			(at 0 -0.4445 270)
			(size 0.1397 0.1397)
			(layers "F.Cu" "F.Mask" "F.Paste")
			(net "I2C_IO_EXP_RESET#_FLT")
			(options
				(clearance outline)
				(anchor circle)
			)
			(primitives
				(gr_poly
					(pts
						(arc
							(start -0.1778 -0.2794)
							(mid -0.249642 -0.249642)
							(end -0.2794 -0.1778)
						)
						(arc
							(start -0.2794 0.1778)
							(mid -0.249642 0.249642)
							(end -0.1778 0.2794)
						)
						(arc
							(start 0.1778 0.2794)
							(mid 0.249642 0.249642)
							(end 0.2794 0.1778)
						)
						(arc
							(start 0.2794 -0.1778)
							(mid 0.249642 -0.249642)
							(end 0.1778 -0.2794)
						)
					)
					(width 0)
					(fill yes)
				)
			)
		)
		(pad "2" smd custom
			(at 0 0.4445 270)
			(size 0.1397 0.1397)
			(layers "F.Cu" "F.Mask" "F.Paste")
			(net "I2C_IO_EXP_RESET#")
			(options
				(clearance outline)
				(anchor circle)
			)
			(primitives
				(gr_poly
					(pts
						(arc
							(start -0.1778 -0.2794)
							(mid -0.249642 -0.249642)
							(end -0.2794 -0.1778)
						)
						(arc
							(start -0.2794 0.1778)
							(mid -0.249642 0.249642)
							(end -0.1778 0.2794)
						)
						(arc
							(start 0.1778 0.2794)
							(mid 0.249642 0.249642)
							(end 0.2794 0.1778)
						)
						(arc
							(start 0.2794 -0.1778)
							(mid 0.249642 -0.249642)
							(end 0.1778 -0.2794)
						)
					)
					(width 0)
					(fill yes)
				)
			)
		)
	)
)
